# BASEBOARD_FAB2 (Tioga Pass) — schematic netlist excerpt (pin names and nets, part order shuffled) for the footprints in the layout excerpt that follows; sources: Cadence DE-HDL packaged netlist, KiCad conversion of Wiwynn_Tioga_Pass_MB.brd

J9L2  SCONN288_H44441003  SCONN  pkg PIP  page 86
  \12v\(1)  = P12V_NVDIMM_KLM
  VSS(93)  = GND
  DQ(4)  = M_L_DQ<4>
  VSS(92)  = GND
  DQ(0)  = M_L_DQ<0>
  VSS(91)  = GND
  DQS9P  = M_L_DQS_DP<9>
  DQS9N  = M_L_DQS_DN<9>
  VSS(90)  = GND
  DQ(6)  = M_L_DQ<6>
  VSS(89)  = GND
  DQ(2)  = M_L_DQ<2>
  VSS(88)  = GND
  DQ(12)  = M_L_DQ<12>
  VSS(87)  = GND
  DQ(8)  = M_L_DQ<8>
  VSS(86)  = GND
  DQS10P  = M_L_DQS_DP<10>
  DQS10N  = M_L_DQS_DN<10>
  VSS(85)  = GND
  DQ(14)  = M_L_DQ<14>
  VSS(84)  = GND
  DQ(10)  = M_L_DQ<10>
  VSS(83)  = GND
  DQ(20)  = M_L_DQ<20>
  VSS(82)  = GND
  DQ(16)  = M_L_DQ<16>
  VSS(81)  = GND
  DQS11P  = M_L_DQS_DP<11>
  DQS11N  = M_L_DQS_DN<11>
  VSS(80)  = GND
  DQ(22)  = M_L_DQ<22>
  VSS(79)  = GND
  DQ(18)  = M_L_DQ<18>
  VSS(78)  = GND
  DQ(28)  = M_L_DQ<28>
  VSS(77)  = GND
  DQ(24)  = M_L_DQ<24>
  VSS(76)  = GND
  DQS12P  = M_L_DQS_DP<12>
  DQS12N  = M_L_DQS_DN<12>
  VSS(75)  = GND
  DQ(30)  = M_L_DQ<30>
  VSS(74)  = GND
  DQ(26)  = M_L_DQ<26>
  VSS(73)  = GND
  CB(4)  = M_L_ECC<4>
  VSS(72)  = GND
  CB(0)  = M_L_ECC<0>
  VSS(71)  = GND
  DQS17P  = M_L_DQS_DP<17>
  DQS17N  = M_L_DQS_DN<17>
  VSS(70)  = GND
  CB(6)  = M_L_ECC<6>
  VSS(69)  = GND
  CB(2)  = M_L_ECC<2>
  VSS(68)  = GND
  RESET_N  = M_KLM_RST_N
  VDD(25)  = PVDDQ_KLM
  CKE(0)  = M_L_CKE<2>
  VDD(24)  = PVDDQ_KLM
  ACT_N  = M_L_ACT_N
  BG(0)  = M_L_BG<0>
  VDD(23)  = PVDDQ_KLM
  A12  = M_L_MA<12>
  A9  = M_L_MA<9>
  VDD(22)  = PVDDQ_KLM
  A8  = M_L_MA<8>
  A6  = M_L_MA<6>
  VDD(21)  = PVDDQ_KLM
  A3  = M_L_MA<3>
  A1  = M_L_MA<1>
  VDD(20)  = PVDDQ_KLM
  CK0P  = M_L_CLK_DP<2>
  CK0N  = M_L_CLK_DN<2>
  VDD(19)  = PVDDQ_KLM
  VTT(1)  = PVTT_KLM
  EVENT_N  = FM_DIMM_EVENT_COD_N
  A0  = M_L_MA<0>
  VDD(18)  = PVDDQ_KLM
  BA(0)  = M_L_BA<0>
  A16_RAS_N  = M_L_MA<16>
  VDD(17)  = PVDDQ_KLM
  S0_N  = M_L_CS_N<4>
  VDD(16)  = PVDDQ_KLM
  A15_CAS_N  = M_L_MA<15>
  ODT(0)  = M_L_ODT<2>
  VDD(15)  = PVDDQ_KLM
  S1_N  = M_L_CS_N<5>
  VDD(14)  = PVDDQ_KLM
  ODT(1)  = M_L_ODT<3>
  VDD(13)  = PVDDQ_KLM
  S2_N_C(0)  = M_L_CS_N<6>
  VSS(67)  = GND
  DQ(36)  = M_L_DQ<36>
  VSS(66)  = GND
  DQ(32)  = M_L_DQ<32>
  VSS(65)  = GND
  DQS13P  = M_L_DQS_DP<13>
  DQS13N  = M_L_DQS_DN<13>
  VSS(64)  = GND
  DQ(38)  = M_L_DQ<38>
  VSS(63)  = GND
  DQ(34)  = M_L_DQ<34>
  VSS(62)  = GND
  DQ(44)  = M_L_DQ<44>
  VSS(61)  = GND
  DQ(40)  = M_L_DQ<40>
  VSS(60)  = GND
  DQS14P  = M_L_DQS_DP<14>
  DQS14N  = M_L_DQS_DN<14>
  VSS(59)  = GND
  DQ(46)  = M_L_DQ<46>
  VSS(58)  = GND
  DQ(42)  = M_L_DQ<42>
  VSS(57)  = GND
  DQ(52)  = M_L_DQ<52>
  VSS(56)  = GND
  DQ(48)  = M_L_DQ<48>
  VSS(55)  = GND
  DQS15P  = M_L_DQS_DP<15>
  DQS15N  = M_L_DQS_DN<15>
  VSS(54)  = GND
  DQ(54)  = M_L_DQ<54>
  VSS(53)  = GND
  DQ(50)  = M_L_DQ<50>
  VSS(52)  = GND
  DQ(60)  = M_L_DQ<60>
  VSS(51)  = GND
  DQ(56)  = M_L_DQ<56>
  VSS(50)  = GND
  DQS16P  = M_L_DQS_DP<16>
  DQS16N  = M_L_DQS_DN<16>
  VSS(49)  = GND
  DQ(62)  = M_L_DQ<62>
  VSS(48)  = GND
  DQ(58)  = M_L_DQ<58>
  VSS(47)  = GND
  SA(0)  = PVPP_KLM
  SA(1)  = PVPP_KLM
  SCL  = SMB_DDR_KLM_VPP_SCL
  VPP(4)  = PVPP_KLM
  VPP(3)  = PVPP_KLM
  RFU(2)  = TP_CH_L_DIMM0_RFU_2
  \12v\(0)  = P12V_NVDIMM_KLM
  VREFCA  = M_L_VREF
  VSS(46)  = GND
  DQ(5)  = M_L_DQ<5>
  VSS(45)  = GND
  DQ(1)  = M_L_DQ<1>
  VSS(44)  = GND
  DQS0N  = M_L_DQS_DN<0>
  DQS0P  = M_L_DQS_DP<0>
  VSS(43)  = GND
  DQ(7)  = M_L_DQ<7>
  VSS(42)  = GND
  DQ(3)  = M_L_DQ<3>
  VSS(41)  = GND
  DQ(13)  = M_L_DQ<13>
  VSS(40)  = GND
  DQ(9)  = M_L_DQ<9>
  VSS(39)  = GND
  DQS1N  = M_L_DQS_DN<1>
  DQS1P  = M_L_DQS_DP<1>
  VSS(38)  = GND
  DQ(15)  = M_L_DQ<15>
  VSS(37)  = GND
  DQ(11)  = M_L_DQ<11>
  VSS(36)  = GND
  DQ(21)  = M_L_DQ<21>
  VSS(35)  = GND
  DQ(17)  = M_L_DQ<17>
  VSS(34)  = GND
  DQS2N  = M_L_DQS_DN<2>
  DQS2P  = M_L_DQS_DP<2>
  VSS(33)  = GND
  DQ(23)  = M_L_DQ<23>
  VSS(32)  = GND
  DQ(19)  = M_L_DQ<19>
  VSS(31)  = GND
  DQ(29)  = M_L_DQ<29>
  VSS(30)  = GND
  DQ(25)  = M_L_DQ<25>
  VSS(29)  = GND
  DQS3N  = M_L_DQS_DN<3>
  DQS3P  = M_L_DQS_DP<3>
  VSS(28)  = GND
  DQ(31)  = M_L_DQ<31>
  VSS(27)  = GND
  DQ(27)  = M_L_DQ<27>
  VSS(26)  = GND
  CB(5)  = M_L_ECC<5>
  VSS(25)  = GND
  CB(1)  = M_L_ECC<1>
  VSS(24)  = GND
  DQS8N  = M_L_DQS_DN<8>
  DQS8P  = M_L_DQS_DP<8>
  VSS(23)  = GND
  CB(7)  = M_L_ECC<7>
  VSS(22)  = GND
  CB(3)  = M_L_ECC<3>
  VSS(21)  = GND
  CKE(1)  = M_L_CKE<3>
  VDD(12)  = PVDDQ_KLM
  RFU(0)  = TP_CH_L_DIMM0_RFU_0
  VDD(11)  = PVDDQ_KLM
  BG(1)  = M_L_BG<1>
  ALERT_N  = M_L_ALERT_N
  VDD(10)  = PVDDQ_KLM
  A11  = M_L_MA<11>
  A7  = M_L_MA<7>
  VDD(9)  = PVDDQ_KLM
  A5  = M_L_MA<5>
  A4  = M_L_MA<4>
  VDD(8)  = PVDDQ_KLM
  A2  = M_L_MA<2>
  VDD(7)  = PVDDQ_KLM
  CK1P  = M_L_CLK_DP<3>
  CK1N  = M_L_CLK_DN<3>
  VDD(6)  = PVDDQ_KLM
  VTT(0)  = PVTT_KLM
  PAR  = M_L_PAR
  VDD(5)  = PVDDQ_KLM
  BA(1)  = M_L_BA<1>
  A10  = M_L_MA<10>
  VDD(4)  = PVDDQ_KLM
  RFU(1)  = TP_CH_L_DIMM0_RFU_1
  A14_WE_N  = M_L_MA<14>
  VDD(3)  = PVDDQ_KLM
  SAVE_N_NC  = FM_ADR_COMPLETE_KLM_N
  VDD(2)  = PVDDQ_KLM
  A13  = M_L_MA<13>
  VDD(1)  = PVDDQ_KLM
  A17  = M_L_MA<17>
  C(2)  = M_L_C<2>
  VDD(0)  = PVDDQ_KLM
  S3_N_C(1)  = M_L_CS_N<7>
  SA(2)  = GND
  VSS(20)  = GND
  DQ(37)  = M_L_DQ<37>
  VSS(19)  = GND
  DQ(33)  = M_L_DQ<33>
  VSS(18)  = GND
  DQS4N  = M_L_DQS_DN<4>
  DQS4P  = M_L_DQS_DP<4>
  VSS(17)  = GND
  DQ(39)  = M_L_DQ<39>
  VSS(16)  = GND
  DQ(35)  = M_L_DQ<35>
  VSS(15)  = GND
  DQ(45)  = M_L_DQ<45>
  VSS(14)  = GND
  DQ(41)  = M_L_DQ<41>
  VSS(13)  = GND
  DQS5N  = M_L_DQS_DN<5>
  DQS5P  = M_L_DQS_DP<5>
  VSS(12)  = GND
  DQ(47)  = M_L_DQ<47>
  VSS(11)  = GND
  DQ(43)  = M_L_DQ<43>
  VSS(10)  = GND
  DQ(53)  = M_L_DQ<53>
  VSS(9)  = GND
  DQ(49)  = M_L_DQ<49>
  VSS(8)  = GND
  DQS6N  = M_L_DQS_DN<6>
  DQS6P  = M_L_DQS_DP<6>
  VSS(7)  = GND
  DQ(55)  = M_L_DQ<55>
  VSS(6)  = GND
  DQ(51)  = M_L_DQ<51>
  VSS(5)  = GND
  DQ(61)  = M_L_DQ<61>
  VSS(4)  = GND
  DQ(57)  = M_L_DQ<57>
  VSS(3)  = GND
  DQS7N  = M_L_DQS_DN<7>
  DQS7P  = M_L_DQS_DP<7>
  VSS(2)  = GND
  DQ(63)  = M_L_DQ<63>
  VSS(1)  = GND
  DQ(59)  = M_L_DQ<59>
  VSS(0)  = GND
  VDDSPD  = PVPP_KLM
  SDA  = SMB_DDR_KLM_VPP_SDA
  VPP(1)  = PVPP_KLM
  VPP(0)  = PVPP_KLM
  VPP(2)  = PVPP_KLM

(kicad_pcb
	(version 20260206)
	(generator "pcbnew")
	(generator_version "10.0")
	(general
		(thickness 1.6)
		(legacy_teardrops no)
	)
	(paper "A4")
	(title_block
		(title "Wiwynn_Tioga_Pass_MB.brd")
		(comment 1 "Tioga Pass / footprint 4281 of 4770 (J9L2), pads 250-291 of 291")
	)
	(layers
		(0 "F.Cu" signal "TOP")
		(4 "In1.Cu" signal "L2GND")
		(6 "In2.Cu" signal "L3")
		(8 "In3.Cu" signal "L4GND")
		(10 "In4.Cu" signal "L5")
		(12 "In5.Cu" signal "L6GND")
		(14 "In6.Cu" signal "L7VCC")
		(16 "In7.Cu" signal "L8VCC")
		(18 "In8.Cu" signal "L9GND")
		(20 "In9.Cu" signal "L10")
		(22 "In10.Cu" signal "L11GND")
		(24 "In11.Cu" signal "L12")
		(26 "In12.Cu" signal "L13GND")
		(2 "B.Cu" signal "BOTTOM")
		(9 "F.Adhes" user "F.Adhesive")
		(11 "B.Adhes" user "B.Adhesive")
		(13 "F.Paste" user "Package Geometry/Pastemask Top")
		(15 "B.Paste" user "Package Geometry/Pastemask Bottom")
		(5 "F.SilkS" user "Ref Des/Silkscreen Top")
		(7 "B.SilkS" user "Ref Des/Silkscreen Bottom")
		(1 "F.Mask" user "Board Geometry/Soldermask Top")
		(3 "B.Mask" user "Board Geometry/Soldermask Bottom")
		(17 "Dwgs.User" user "User.Drawings")
		(19 "Cmts.User" user "User.Comments")
		(21 "Eco1.User" user "User.Eco1")
		(23 "Eco2.User" user "User.Eco2")
		(25 "Edge.Cuts" user "Board Geometry/Outline")
		(27 "Margin" user)
		(31 "F.CrtYd" user "Package Geometry/Place Bound Top")
		(29 "B.CrtYd" user "Package Geometry/Place Bound Bottom")
		(35 "F.Fab" user "Ref Des/Assembly Top")
		(33 "B.Fab" user "Ref Des/Assembly Bottom")
	)
	(footprint ""
		(layer "B.Cu")
		(at 29.699458 -142.477236 90)
		(property "Reference" "J9L2"
			(at 2.403348 38.118542 0)
			(unlocked yes)
			(layer "B.SilkS")
			(effects
				(font
					(size 0.7874 0.5842)
					(thickness 0.1524)
				)
				(justify left mirror)
			)
		)
		(property "Value" ""
			(at 0 0 90)
			(layer "B.Fab")
			(effects
				(font
					(size 1.27 1.27)
				)
				(justify mirror)
			)
		)
		(duplicate_pad_numbers_are_jumpers no)
		(pad "247" smd rect
			(at -4.59994 91.799918 270)
			(size 1.8034 0.508)
			(layers "B.Cu" "B.Mask" "B.Paste")
			(net "M_L_DQ<39>")
		)
		(pad "248" smd rect
			(at -4.59994 92.650056 270)
			(size 1.8034 0.508)
			(layers "B.Cu" "B.Mask" "B.Paste")
			(net "GND")
		)
		(pad "249" smd rect
			(at -4.59994 93.49994 270)
			(size 1.8034 0.508)
			(layers "B.Cu" "B.Mask" "B.Paste")
			(net "M_L_DQ<35>")
		)
		(pad "250" smd rect
			(at -4.59994 94.350078 270)
			(size 1.8034 0.508)
			(layers "B.Cu" "B.Mask" "B.Paste")
			(net "GND")
		)
		(pad "251" smd rect
			(at -4.59994 95.199962 270)
			(size 1.8034 0.508)
			(layers "B.Cu" "B.Mask" "B.Paste")
			(net "M_L_DQ<45>")
		)
		(pad "252" smd rect
			(at -4.59994 96.0501 270)
			(size 1.8034 0.508)
			(layers "B.Cu" "B.Mask" "B.Paste")
			(net "GND")
		)
		(pad "253" smd rect
			(at -4.59994 96.899984 270)
			(size 1.8034 0.508)
			(layers "B.Cu" "B.Mask" "B.Paste")
			(net "M_L_DQ<41>")
		)
		(pad "254" smd rect
			(at -4.59994 97.750122 270)
			(size 1.8034 0.508)
			(layers "B.Cu" "B.Mask" "B.Paste")
			(net "GND")
		)
		(pad "255" smd rect
			(at -4.59994 98.600006 270)
			(size 1.8034 0.508)
			(layers "B.Cu" "B.Mask" "B.Paste")
			(net "M_L_DQS_DN<5>")
		)
		(pad "256" smd rect
			(at -4.59994 99.44989 270)
			(size 1.8034 0.508)
			(layers "B.Cu" "B.Mask" "B.Paste")
			(net "M_L_DQS_DP<5>")
		)
		(pad "257" smd rect
			(at -4.59994 100.300028 270)
			(size 1.8034 0.508)
			(layers "B.Cu" "B.Mask" "B.Paste")
			(net "GND")
		)
		(pad "258" smd rect
			(at -4.59994 101.149912 270)
			(size 1.8034 0.508)
			(layers "B.Cu" "B.Mask" "B.Paste")
			(net "M_L_DQ<47>")
		)
		(pad "259" smd rect
			(at -4.59994 102.00005 270)
			(size 1.8034 0.508)
			(layers "B.Cu" "B.Mask" "B.Paste")
			(net "GND")
		)
		(pad "260" smd rect
			(at -4.59994 102.849934 270)
			(size 1.8034 0.508)
			(layers "B.Cu" "B.Mask" "B.Paste")
			(net "M_L_DQ<43>")
		)
		(pad "261" smd rect
			(at -4.59994 103.700072 270)
			(size 1.8034 0.508)
			(layers "B.Cu" "B.Mask" "B.Paste")
			(net "GND")
		)
		(pad "262" smd rect
			(at -4.59994 104.549956 270)
			(size 1.8034 0.508)
			(layers "B.Cu" "B.Mask" "B.Paste")
			(net "M_L_DQ<53>")
		)
		(pad "263" smd rect
			(at -4.59994 105.400094 270)
			(size 1.8034 0.508)
			(layers "B.Cu" "B.Mask" "B.Paste")
			(net "GND")
		)
		(pad "264" smd rect
			(at -4.59994 106.249978 270)
			(size 1.8034 0.508)
			(layers "B.Cu" "B.Mask" "B.Paste")
			(net "M_L_DQ<49>")
		)
		(pad "265" smd rect
			(at -4.59994 107.100116 270)
			(size 1.8034 0.508)
			(layers "B.Cu" "B.Mask" "B.Paste")
			(net "GND")
		)
		(pad "266" smd rect
			(at -4.59994 107.95 270)
			(size 1.8034 0.508)
			(layers "B.Cu" "B.Mask" "B.Paste")
			(net "M_L_DQS_DN<6>")
		)
		(pad "267" smd rect
			(at -4.59994 108.799884 270)
			(size 1.8034 0.508)
			(layers "B.Cu" "B.Mask" "B.Paste")
			(net "M_L_DQS_DP<6>")
		)
		(pad "268" smd rect
			(at -4.59994 109.650022 270)
			(size 1.8034 0.508)
			(layers "B.Cu" "B.Mask" "B.Paste")
			(net "GND")
		)
		(pad "269" smd rect
			(at -4.59994 110.499906 270)
			(size 1.8034 0.508)
			(layers "B.Cu" "B.Mask" "B.Paste")
			(net "M_L_DQ<55>")
		)
		(pad "270" smd rect
			(at -4.59994 111.350044 270)
			(size 1.8034 0.508)
			(layers "B.Cu" "B.Mask" "B.Paste")
			(net "GND")
		)
		(pad "271" smd rect
			(at -4.59994 112.199928 270)
			(size 1.8034 0.508)
			(layers "B.Cu" "B.Mask" "B.Paste")
			(net "M_L_DQ<51>")
		)
		(pad "272" smd rect
			(at -4.59994 113.050066 270)
			(size 1.8034 0.508)
			(layers "B.Cu" "B.Mask" "B.Paste")
			(net "GND")
		)
		(pad "273" smd rect
			(at -4.59994 113.89995 270)
			(size 1.8034 0.508)
			(layers "B.Cu" "B.Mask" "B.Paste")
			(net "M_L_DQ<61>")
		)
		(pad "274" smd rect
			(at -4.59994 114.750088 270)
			(size 1.8034 0.508)
			(layers "B.Cu" "B.Mask" "B.Paste")
			(net "GND")
		)
		(pad "275" smd rect
			(at -4.59994 115.599972 270)
			(size 1.8034 0.508)
			(layers "B.Cu" "B.Mask" "B.Paste")
			(net "M_L_DQ<57>")
		)
		(pad "276" smd rect
			(at -4.59994 116.45011 270)
			(size 1.8034 0.508)
			(layers "B.Cu" "B.Mask" "B.Paste")
			(net "GND")
		)
		(pad "277" smd rect
			(at -4.59994 117.299994 270)
			(size 1.8034 0.508)
			(layers "B.Cu" "B.Mask" "B.Paste")
			(net "M_L_DQS_DN<7>")
		)
		(pad "278" smd rect
			(at -4.59994 118.149878 270)
			(size 1.8034 0.508)
			(layers "B.Cu" "B.Mask" "B.Paste")
			(net "M_L_DQS_DP<7>")
		)
		(pad "279" smd rect
			(at -4.59994 119.000016 270)
			(size 1.8034 0.508)
			(layers "B.Cu" "B.Mask" "B.Paste")
			(net "GND")
		)
		(pad "280" smd rect
			(at -4.59994 119.8499 270)
			(size 1.8034 0.508)
			(layers "B.Cu" "B.Mask" "B.Paste")
			(net "M_L_DQ<63>")
		)
		(pad "281" smd rect
			(at -4.59994 120.700038 270)
			(size 1.8034 0.508)
			(layers "B.Cu" "B.Mask" "B.Paste")
			(net "GND")
		)
		(pad "282" smd rect
			(at -4.59994 121.549922 270)
			(size 1.8034 0.508)
			(layers "B.Cu" "B.Mask" "B.Paste")
			(net "M_L_DQ<59>")
		)
		(pad "283" smd rect
			(at -4.59994 122.40006 270)
			(size 1.8034 0.508)
			(layers "B.Cu" "B.Mask" "B.Paste")
			(net "GND")
		)
		(pad "284" smd rect
			(at -4.59994 123.249944 270)
			(size 1.8034 0.508)
			(layers "B.Cu" "B.Mask" "B.Paste")
			(net "PVPP_KLM")
		)
		(pad "285" smd rect
			(at -4.59994 124.100082 270)
			(size 1.8034 0.508)
			(layers "B.Cu" "B.Mask" "B.Paste")
			(net "SMB_DDR_KLM_VPP_SDA")
		)
		(pad "286" smd rect
			(at -4.59994 124.949966 270)
			(size 1.8034 0.508)
			(layers "B.Cu" "B.Mask" "B.Paste")
			(net "PVPP_KLM")
		)
		(pad "287" smd rect
			(at -4.59994 125.800104 270)
			(size 1.8034 0.508)
			(layers "B.Cu" "B.Mask" "B.Paste")
			(net "PVPP_KLM")
		)
		(pad "288" smd rect
			(at -4.59994 126.649988 270)
			(size 1.8034 0.508)
			(layers "B.Cu" "B.Mask" "B.Paste")
			(net "PVPP_KLM")
		)
	)
)
